FILE_TYPE = MULTI_PHYS_TABLE;

PART 'TS3USB3031RMGR_WQFN12'
CLASS = IC

{========================================================================================}
: CLS_PN        |    VALUE          =  JEDEC_TYPE                        | ALT_SYMBOLS                         | DESCRIPTION                            ;
{========================================================================================}
 'G220-10368-01'  |    'TS3USB3031RMGR'    = 'QFN12_071_P0157'  |'(QFN12_071_P0157)'  |'IC,DUAL USB 2.0 HS,5.5V,12P,WQFN,SMT'  

END_PART

END.

